(kicad_pcb
	(version 20260206)
	(generator "pcbnew")
	(generator_version "10.0")
	(general
		(thickness 1.6)
		(legacy_teardrops no)
	)
	(paper "A4")
	(title_block
		(title "01162023_DA0F0TEBIF0_F0T_Expander_BD_F_brd_V02_OCP.brd")
		(comment 1 "Grand Teton / footprints 6707-6713 of 9728")
	)
	(layers
		(0 "F.Cu" signal "TOP")
		(4 "In1.Cu" signal "GND")
		(6 "In2.Cu" signal "VCC")
		(8 "In3.Cu" signal "VCC1")
		(10 "In4.Cu" signal "GND1")
		(12 "In5.Cu" signal "IN1")
		(14 "In6.Cu" signal "GND2")
		(16 "In7.Cu" signal "IN2")
		(18 "In8.Cu" signal "GND3")
		(20 "In9.Cu" signal "IN3")
		(22 "In10.Cu" signal "GND4")
		(24 "In11.Cu" signal "IN4")
		(26 "In12.Cu" signal "GND5")
		(28 "In13.Cu" signal "IN5")
		(30 "In14.Cu" signal "GND6")
		(32 "In15.Cu" signal "IN6")
		(34 "In16.Cu" signal "GND7")
		(2 "B.Cu" signal "BOTTOM")
		(9 "F.Adhes" user "F.Adhesive")
		(11 "B.Adhes" user "B.Adhesive")
		(13 "F.Paste" user "Package Geometry/Pastemask Top")
		(15 "B.Paste" user "Package Geometry/Pastemask Bottom")
		(5 "F.SilkS" user "Ref Des/Silkscreen Top")
		(7 "B.SilkS" user "Ref Des/Silkscreen Bottom")
		(1 "F.Mask" user "Board Geometry/Soldermask Top")
		(3 "B.Mask" user "Board Geometry/Soldermask Bottom")
		(17 "Dwgs.User" user "User.Drawings")
		(19 "Cmts.User" user "User.Comments")
		(21 "Eco1.User" user "User.Eco1")
		(23 "Eco2.User" user "User.Eco2")
		(25 "Edge.Cuts" user "Board Geometry/Outline")
		(27 "Margin" user)
		(31 "F.CrtYd" user "Package Geometry/Place Bound Top")
		(29 "B.CrtYd" user "Package Geometry/Place Bound Bottom")
		(35 "F.Fab" user "Ref Des/Assembly Top")
		(33 "B.Fab" user "Ref Des/Assembly Bottom")
	)
	(footprint ""
		(layer "F.Cu")
		(at 459.5368 -308.285896 90)
		(property "Reference" "PC282"
			(at 0 0 90)
			(layer "F.SilkS")
			(hide yes)
			(effects
				(font
					(size 1.27 1.27)
				)
			)
		)
		(property "Value" ""
			(at 0 0 90)
			(layer "F.Fab")
			(effects
				(font
					(size 1.27 1.27)
				)
			)
		)
		(duplicate_pad_numbers_are_jumpers no)
		(fp_line
			(start 0.7874 -0.4064)
			(end 0.7874 0.4064)
			(stroke
				(width 0.1524)
				(type default)
			)
			(layer "F.SilkS")
		)
		(fp_line
			(start -0.7874 -0.4064)
			(end 0.7874 -0.4064)
			(stroke
				(width 0.1524)
				(type default)
			)
			(layer "F.SilkS")
		)
		(fp_line
			(start 0.7874 0.4064)
			(end -0.7874 0.4064)
			(stroke
				(width 0.1524)
				(type default)
			)
			(layer "F.SilkS")
		)
		(fp_line
			(start -0.7874 0.4064)
			(end -0.7874 -0.4064)
			(stroke
				(width 0.1524)
				(type default)
			)
			(layer "F.SilkS")
		)
		(fp_line
			(start -0.12065 -0.305054)
			(end -0.12065 -0.2794)
			(stroke
				(width 0.1)
				(type default)
			)
			(layer "F.Fab")
		)
		(fp_line
			(start -0.67945 -0.305054)
			(end -0.12065 -0.305054)
			(stroke
				(width 0.1)
				(type default)
			)
			(layer "F.Fab")
		)
		(fp_line
			(start 0.67945 -0.3048)
			(end 0.67945 0.3048)
			(stroke
				(width 0.1)
				(type default)
			)
			(layer "F.Fab")
		)
		(fp_line
			(start 0.12065 -0.3048)
			(end 0.67945 -0.3048)
			(stroke
				(width 0.1)
				(type default)
			)
			(layer "F.Fab")
		)
		(fp_line
			(start 0.12065 -0.2794)
			(end 0.12065 -0.3048)
			(stroke
				(width 0.1)
				(type default)
			)
			(layer "F.Fab")
		)
		(fp_line
			(start -0.12065 -0.2794)
			(end 0.12065 -0.2794)
			(stroke
				(width 0.1)
				(type default)
			)
			(layer "F.Fab")
		)
		(fp_line
			(start 0.120396 0.2794)
			(end -0.12065 0.2794)
			(stroke
				(width 0.1)
				(type default)
			)
			(layer "F.Fab")
		)
		(fp_line
			(start -0.12065 0.2794)
			(end -0.12065 0.3048)
			(stroke
				(width 0.1)
				(type default)
			)
			(layer "F.Fab")
		)
		(fp_line
			(start 0.67945 0.3048)
			(end 0.120396 0.3048)
			(stroke
				(width 0.1)
				(type default)
			)
			(layer "F.Fab")
		)
		(fp_line
			(start 0.120396 0.3048)
			(end 0.120396 0.2794)
			(stroke
				(width 0.1)
				(type default)
			)
			(layer "F.Fab")
		)
		(fp_line
			(start -0.12065 0.3048)
			(end -0.67945 0.3048)
			(stroke
				(width 0.1)
				(type default)
			)
			(layer "F.Fab")
		)
		(fp_line
			(start -0.67945 0.3048)
			(end -0.67945 -0.305054)
			(stroke
				(width 0.1)
				(type default)
			)
			(layer "F.Fab")
		)
		(pad "1" smd circle
			(at -0.40005 0 90)
			(size 0 0)
			(layers "F.Cu" "F.Mask" "F.Paste")
			(net "P1V25_PEX3_REF")
		)
		(pad "2" smd circle
			(at 0.40005 0 90)
			(size 0 0)
			(layers "F.Cu" "F.Mask" "F.Paste")
			(net "SH_P1V25_PEX3_FB_N")
		)
	)
	(footprint ""
		(layer "F.Cu")
		(at 428.319438 -147.104608 180)
		(property "Reference" "C644"
			(at 0 0 180)
			(layer "F.SilkS")
			(hide yes)
			(effects
				(font
					(size 1.27 1.27)
				)
			)
		)
		(property "Value" ""
			(at 0 0 180)
			(layer "F.Fab")
			(effects
				(font
					(size 1.27 1.27)
				)
			)
		)
		(duplicate_pad_numbers_are_jumpers no)
		(fp_line
			(start 0.299974 0.150114)
			(end -0.299974 0.150114)
			(stroke
				(width 0.1)
				(type default)
			)
			(layer "F.Fab")
		)
		(fp_line
			(start 0.299974 -0.150114)
			(end 0.299974 0.150114)
			(stroke
				(width 0.1)
				(type default)
			)
			(layer "F.Fab")
		)
		(fp_line
			(start -0.299974 0.150114)
			(end -0.299974 -0.150114)
			(stroke
				(width 0.1)
				(type default)
			)
			(layer "F.Fab")
		)
		(fp_line
			(start -0.299974 -0.150114)
			(end 0.299974 -0.150114)
			(stroke
				(width 0.1)
				(type default)
			)
			(layer "F.Fab")
		)
		(pad "1" smd rect
			(at -0.2667 0 180)
			(size 0.3048 0.381)
			(layers "F.Cu" "F.Mask" "F.Paste")
			(net "P5E_PEX3_STN0_TX_DP<10>")
		)
		(pad "2" smd rect
			(at 0.2667 0 180)
			(size 0.3048 0.381)
			(layers "F.Cu" "F.Mask" "F.Paste")
			(net "P5E_PEX3_STN0_TX_C_DP<10>")
		)
	)
	(footprint ""
		(layer "F.Cu")
		(at 429.175164 -64.102234 180)
		(property "Reference" "PR7098"
			(at 0 0 180)
			(layer "F.SilkS")
			(hide yes)
			(effects
				(font
					(size 1.27 1.27)
				)
			)
		)
		(property "Value" ""
			(at 0 0 180)
			(layer "F.Fab")
			(effects
				(font
					(size 1.27 1.27)
				)
			)
		)
		(duplicate_pad_numbers_are_jumpers no)
		(fp_line
			(start 0.7874 0.4064)
			(end -0.7874 0.4064)
			(stroke
				(width 0.1524)
				(type default)
			)
			(layer "F.SilkS")
		)
		(fp_line
			(start 0.7874 -0.4064)
			(end 0.7874 0.4064)
			(stroke
				(width 0.1524)
				(type default)
			)
			(layer "F.SilkS")
		)
		(fp_line
			(start -0.7874 0.4064)
			(end -0.7874 -0.4064)
			(stroke
				(width 0.1524)
				(type default)
			)
			(layer "F.SilkS")
		)
		(fp_line
			(start -0.7874 -0.4064)
			(end 0.7874 -0.4064)
			(stroke
				(width 0.1524)
				(type default)
			)
			(layer "F.SilkS")
		)
		(fp_line
			(start 0.67945 0.3048)
			(end 0.120396 0.3048)
			(stroke
				(width 0.1)
				(type default)
			)
			(layer "F.Fab")
		)
		(fp_line
			(start 0.67945 -0.3048)
			(end 0.67945 0.3048)
			(stroke
				(width 0.1)
				(type default)
			)
			(layer "F.Fab")
		)
		(fp_line
			(start 0.12065 -0.2794)
			(end 0.12065 -0.3048)
			(stroke
				(width 0.1)
				(type default)
			)
			(layer "F.Fab")
		)
		(fp_line
			(start 0.12065 -0.3048)
			(end 0.67945 -0.3048)
			(stroke
				(width 0.1)
				(type default)
			)
			(layer "F.Fab")
		)
		(fp_line
			(start 0.120396 0.3048)
			(end 0.120396 0.2794)
			(stroke
				(width 0.1)
				(type default)
			)
			(layer "F.Fab")
		)
		(fp_line
			(start 0.120396 0.2794)
			(end -0.12065 0.2794)
			(stroke
				(width 0.1)
				(type default)
			)
			(layer "F.Fab")
		)
		(fp_line
			(start -0.12065 0.3048)
			(end -0.67945 0.3048)
			(stroke
				(width 0.1)
				(type default)
			)
			(layer "F.Fab")
		)
		(fp_line
			(start -0.12065 0.2794)
			(end -0.12065 0.3048)
			(stroke
				(width 0.1)
				(type default)
			)
			(layer "F.Fab")
		)
		(fp_line
			(start -0.12065 -0.2794)
			(end 0.12065 -0.2794)
			(stroke
				(width 0.1)
				(type default)
			)
			(layer "F.Fab")
		)
		(fp_line
			(start -0.12065 -0.305054)
			(end -0.12065 -0.2794)
			(stroke
				(width 0.1)
				(type default)
			)
			(layer "F.Fab")
		)
		(fp_line
			(start -0.67945 0.3048)
			(end -0.67945 -0.305054)
			(stroke
				(width 0.1)
				(type default)
			)
			(layer "F.Fab")
		)
		(fp_line
			(start -0.67945 -0.305054)
			(end -0.12065 -0.305054)
			(stroke
				(width 0.1)
				(type default)
			)
			(layer "F.Fab")
		)
		(pad "1" smd circle
			(at -0.40005 0 180)
			(size 0 0)
			(layers "F.Cu" "F.Mask" "F.Paste")
			(net "P12V_SSD15_PG_G1")
		)
		(pad "2" smd circle
			(at 0.40005 0 180)
			(size 0 0)
			(layers "F.Cu" "F.Mask" "F.Paste")
			(net "GND")
		)
	)
	(footprint ""
		(layer "F.Cu")
		(at 88.495886 -310.509412 135)
		(property "Reference" "R1238"
			(at 0 0 135)
			(layer "F.SilkS")
			(hide yes)
			(effects
				(font
					(size 1.27 1.27)
				)
			)
		)
		(property "Value" ""
			(at 0 0 135)
			(layer "F.Fab")
			(effects
				(font
					(size 1.27 1.27)
				)
			)
		)
		(duplicate_pad_numbers_are_jumpers no)
		(fp_line
			(start 0.787389 -0.406267)
			(end 0.787389 0.406267)
			(stroke
				(width 0.1524)
				(type default)
			)
			(layer "F.SilkS")
		)
		(fp_line
			(start 0.787389 0.406267)
			(end -0.787389 0.406267)
			(stroke
				(width 0.1524)
				(type default)
			)
			(layer "F.SilkS")
		)
		(fp_line
			(start -0.787389 -0.406267)
			(end 0.787389 -0.406267)
			(stroke
				(width 0.1524)
				(type default)
			)
			(layer "F.SilkS")
		)
		(fp_line
			(start -0.787389 0.406267)
			(end -0.787389 -0.406267)
			(stroke
				(width 0.1524)
				(type default)
			)
			(layer "F.SilkS")
		)
		(fp_line
			(start 0.679446 -0.30479)
			(end 0.679446 0.30479)
			(stroke
				(width 0.1)
				(type default)
			)
			(layer "F.Fab")
		)
		(fp_line
			(start 0.120515 -0.30479)
			(end 0.679446 -0.30479)
			(stroke
				(width 0.1)
				(type default)
			)
			(layer "F.Fab")
		)
		(fp_line
			(start 0.120695 -0.279466)
			(end 0.120515 -0.30479)
			(stroke
				(width 0.1)
				(type default)
			)
			(layer "F.Fab")
		)
		(fp_line
			(start 0.679446 0.30479)
			(end 0.120515 0.30479)
			(stroke
				(width 0.1)
				(type default)
			)
			(layer "F.Fab")
		)
		(fp_line
			(start -0.120695 -0.304969)
			(end -0.120695 -0.279466)
			(stroke
				(width 0.1)
				(type default)
			)
			(layer "F.Fab")
		)
		(fp_line
			(start -0.120695 -0.279466)
			(end 0.120695 -0.279466)
			(stroke
				(width 0.1)
				(type default)
			)
			(layer "F.Fab")
		)
		(fp_line
			(start 0.120335 0.279466)
			(end -0.120695 0.279466)
			(stroke
				(width 0.1)
				(type default)
			)
			(layer "F.Fab")
		)
		(fp_line
			(start 0.120515 0.30479)
			(end 0.120335 0.279466)
			(stroke
				(width 0.1)
				(type default)
			)
			(layer "F.Fab")
		)
		(fp_line
			(start -0.679446 -0.305149)
			(end -0.120695 -0.304969)
			(stroke
				(width 0.1)
				(type default)
			)
			(layer "F.Fab")
		)
		(fp_line
			(start -0.120695 0.279466)
			(end -0.120515 0.30479)
			(stroke
				(width 0.1)
				(type default)
			)
			(layer "F.Fab")
		)
		(fp_line
			(start -0.120515 0.30479)
			(end -0.679446 0.30479)
			(stroke
				(width 0.1)
				(type default)
			)
			(layer "F.Fab")
		)
		(fp_line
			(start -0.679446 0.30479)
			(end -0.679446 -0.305149)
			(stroke
				(width 0.1)
				(type default)
			)
			(layer "F.Fab")
		)
		(pad "1" smd circle
			(at -0.40005 0 135)
			(size 0 0)
			(layers "F.Cu" "F.Mask" "F.Paste")
			(net "PEX0_SPARE2")
		)
		(pad "2" smd circle
			(at 0.40005 0 135)
			(size 0 0)
			(layers "F.Cu" "F.Mask" "F.Paste")
			(net "P1V8_PEX")
		)
	)
	(footprint ""
		(layer "F.Cu")
		(at 278.112982 -343.952322 90)
		(property "Reference" "C606"
			(at 0 0 90)
			(layer "F.SilkS")
			(hide yes)
			(effects
				(font
					(size 1.27 1.27)
				)
			)
		)
		(property "Value" ""
			(at 0 0 90)
			(layer "F.Fab")
			(effects
				(font
					(size 1.27 1.27)
				)
			)
		)
		(duplicate_pad_numbers_are_jumpers no)
		(fp_line
			(start 0.299974 -0.150114)
			(end 0.299974 0.150114)
			(stroke
				(width 0.1)
				(type default)
			)
			(layer "F.Fab")
		)
		(fp_line
			(start -0.299974 -0.150114)
			(end 0.299974 -0.150114)
			(stroke
				(width 0.1)
				(type default)
			)
			(layer "F.Fab")
		)
		(fp_line
			(start 0.299974 0.150114)
			(end -0.299974 0.150114)
			(stroke
				(width 0.1)
				(type default)
			)
			(layer "F.Fab")
		)
		(fp_line
			(start -0.299974 0.150114)
			(end -0.299974 -0.150114)
			(stroke
				(width 0.1)
				(type default)
			)
			(layer "F.Fab")
		)
		(pad "1" smd rect
			(at -0.2667 0 90)
			(size 0.3048 0.381)
			(layers "F.Cu" "F.Mask" "F.Paste")
			(net "P5E_PEX2_STN7_TX_DN<116>")
		)
		(pad "2" smd rect
			(at 0.2667 0 90)
			(size 0.3048 0.381)
			(layers "F.Cu" "F.Mask" "F.Paste")
			(net "P5E_PEX2_STN7_TX_C_DN<116>")
		)
	)
	(footprint ""
		(layer "F.Cu")
		(at 437.42229 -102.319328 45)
		(property "Reference" "C624"
			(at 0 0 45)
			(layer "F.SilkS")
			(hide yes)
			(effects
				(font
					(size 1.27 1.27)
				)
			)
		)
		(property "Value" ""
			(at 0 0 45)
			(layer "F.Fab")
			(effects
				(font
					(size 1.27 1.27)
				)
			)
		)
		(duplicate_pad_numbers_are_jumpers no)
		(fp_line
			(start -0.787389 -0.406267)
			(end 0.787389 -0.406267)
			(stroke
				(width 0.1524)
				(type default)
			)
			(layer "F.SilkS")
		)
		(fp_line
			(start -0.787389 0.406267)
			(end -0.787389 -0.406267)
			(stroke
				(width 0.1524)
				(type default)
			)
			(layer "F.SilkS")
		)
		(fp_line
			(start 0.787389 -0.406267)
			(end 0.787389 0.406267)
			(stroke
				(width 0.1524)
				(type default)
			)
			(layer "F.SilkS")
		)
		(fp_line
			(start 0.787389 0.406267)
			(end -0.787389 0.406267)
			(stroke
				(width 0.1524)
				(type default)
			)
			(layer "F.SilkS")
		)
		(fp_line
			(start -0.679446 -0.305149)
			(end -0.120695 -0.304969)
			(stroke
				(width 0.1)
				(type default)
			)
			(layer "F.Fab")
		)
		(fp_line
			(start -0.120695 -0.304969)
			(end -0.120695 -0.279466)
			(stroke
				(width 0.1)
				(type default)
			)
			(layer "F.Fab")
		)
		(fp_line
			(start -0.120695 -0.279466)
			(end 0.120695 -0.279466)
			(stroke
				(width 0.1)
				(type default)
			)
			(layer "F.Fab")
		)
		(fp_line
			(start -0.679446 0.30479)
			(end -0.679446 -0.305149)
			(stroke
				(width 0.1)
				(type default)
			)
			(layer "F.Fab")
		)
		(fp_line
			(start 0.120515 -0.30479)
			(end 0.679446 -0.30479)
			(stroke
				(width 0.1)
				(type default)
			)
			(layer "F.Fab")
		)
		(fp_line
			(start 0.120695 -0.279466)
			(end 0.120515 -0.30479)
			(stroke
				(width 0.1)
				(type default)
			)
			(layer "F.Fab")
		)
		(fp_line
			(start -0.120695 0.279466)
			(end -0.120515 0.30479)
			(stroke
				(width 0.1)
				(type default)
			)
			(layer "F.Fab")
		)
		(fp_line
			(start -0.120515 0.30479)
			(end -0.679446 0.30479)
			(stroke
				(width 0.1)
				(type default)
			)
			(layer "F.Fab")
		)
		(fp_line
			(start 0.679446 -0.30479)
			(end 0.679446 0.30479)
			(stroke
				(width 0.1)
				(type default)
			)
			(layer "F.Fab")
		)
		(fp_line
			(start 0.120335 0.279466)
			(end -0.120695 0.279466)
			(stroke
				(width 0.1)
				(type default)
			)
			(layer "F.Fab")
		)
		(fp_line
			(start 0.120515 0.30479)
			(end 0.120335 0.279466)
			(stroke
				(width 0.1)
				(type default)
			)
			(layer "F.Fab")
		)
		(fp_line
			(start 0.679446 0.30479)
			(end 0.120515 0.30479)
			(stroke
				(width 0.1)
				(type default)
			)
			(layer "F.Fab")
		)
		(pad "1" smd circle
			(at -0.40005 0 45)
			(size 0 0)
			(layers "F.Cu" "F.Mask" "F.Paste")
			(net "P12V_NIC7_VIN_P")
		)
		(pad "2" smd circle
			(at 0.40005 0 45)
			(size 0 0)
			(layers "F.Cu" "F.Mask" "F.Paste")
			(net "P12V_NIC7_VIN_N")
		)
	)
	(footprint ""
		(layer "F.Cu")
		(at 89.12225 -102.319328 45)
		(property "Reference" "C414"
			(at 0 0 45)
			(layer "F.SilkS")
			(hide yes)
			(effects
				(font
					(size 1.27 1.27)
				)
			)
		)
		(property "Value" ""
			(at 0 0 45)
			(layer "F.Fab")
			(effects
				(font
					(size 1.27 1.27)
				)
			)
		)
		(duplicate_pad_numbers_are_jumpers no)
		(fp_line
			(start -0.787389 -0.406267)
			(end 0.787389 -0.406267)
			(stroke
				(width 0.1524)
				(type default)
			)
			(layer "F.SilkS")
		)
		(fp_line
			(start -0.787389 0.406267)
			(end -0.787389 -0.406267)
			(stroke
				(width 0.1524)
				(type default)
			)
			(layer "F.SilkS")
		)
		(fp_line
			(start 0.787389 -0.406267)
			(end 0.787389 0.406267)
			(stroke
				(width 0.1524)
				(type default)
			)
			(layer "F.SilkS")
		)
		(fp_line
			(start 0.787389 0.406267)
			(end -0.787389 0.406267)
			(stroke
				(width 0.1524)
				(type default)
			)
			(layer "F.SilkS")
		)
		(fp_line
			(start -0.679446 -0.305149)
			(end -0.120695 -0.304969)
			(stroke
				(width 0.1)
				(type default)
			)
			(layer "F.Fab")
		)
		(fp_line
			(start -0.120695 -0.304969)
			(end -0.120695 -0.279466)
			(stroke
				(width 0.1)
				(type default)
			)
			(layer "F.Fab")
		)
		(fp_line
			(start -0.120695 -0.279466)
			(end 0.120695 -0.279466)
			(stroke
				(width 0.1)
				(type default)
			)
			(layer "F.Fab")
		)
		(fp_line
			(start -0.679446 0.30479)
			(end -0.679446 -0.305149)
			(stroke
				(width 0.1)
				(type default)
			)
			(layer "F.Fab")
		)
		(fp_line
			(start 0.120515 -0.30479)
			(end 0.679446 -0.30479)
			(stroke
				(width 0.1)
				(type default)
			)
			(layer "F.Fab")
		)
		(fp_line
			(start 0.120695 -0.279466)
			(end 0.120515 -0.30479)
			(stroke
				(width 0.1)
				(type default)
			)
			(layer "F.Fab")
		)
		(fp_line
			(start -0.120695 0.279466)
			(end -0.120515 0.30479)
			(stroke
				(width 0.1)
				(type default)
			)
			(layer "F.Fab")
		)
		(fp_line
			(start -0.120515 0.30479)
			(end -0.679446 0.30479)
			(stroke
				(width 0.1)
				(type default)
			)
			(layer "F.Fab")
		)
		(fp_line
			(start 0.679446 -0.30479)
			(end 0.679446 0.30479)
			(stroke
				(width 0.1)
				(type default)
			)
			(layer "F.Fab")
		)
		(fp_line
			(start 0.120335 0.279466)
			(end -0.120695 0.279466)
			(stroke
				(width 0.1)
				(type default)
			)
			(layer "F.Fab")
		)
		(fp_line
			(start 0.120515 0.30479)
			(end 0.120335 0.279466)
			(stroke
				(width 0.1)
				(type default)
			)
			(layer "F.Fab")
		)
		(fp_line
			(start 0.679446 0.30479)
			(end 0.120515 0.30479)
			(stroke
				(width 0.1)
				(type default)
			)
			(layer "F.Fab")
		)
		(pad "1" smd circle
			(at -0.40005 0 45)
			(size 0 0)
			(layers "F.Cu" "F.Mask" "F.Paste")
			(net "P12V_NIC1_VIN_P")
		)
		(pad "2" smd circle
			(at 0.40005 0 45)
			(size 0 0)
			(layers "F.Cu" "F.Mask" "F.Paste")
			(net "P12V_NIC1_VIN_N")
		)
	)
)
